(kicad_pcb
	(version 20260206)
	(generator "pcbnew")
	(generator_version "10.0")
	(general
		(thickness 1.6)
		(legacy_teardrops no)
	)
	(paper "A4")
	(title_block
		(title "Bryce Canyon_R.DPB_16317-1_OCP.brd")
		(comment 1 "Bryce Canyon / footprints 1173-1179 of 2099")
	)
	(layers
		(0 "F.Cu" signal "TOP")
		(4 "In1.Cu" signal "L2GND")
		(6 "In2.Cu" signal "L3")
		(8 "In3.Cu" signal "L4VCC")
		(10 "In4.Cu" signal "L5VCC")
		(12 "In5.Cu" signal "L6")
		(14 "In6.Cu" signal "L7GND")
		(2 "B.Cu" signal "BOTTOM")
		(9 "F.Adhes" user "F.Adhesive")
		(11 "B.Adhes" user "B.Adhesive")
		(13 "F.Paste" user "Package Geometry/Pastemask Top")
		(15 "B.Paste" user "Package Geometry/Pastemask Bottom")
		(5 "F.SilkS" user "Ref Des/Silkscreen Top")
		(7 "B.SilkS" user "Ref Des/Silkscreen Bottom")
		(1 "F.Mask" user "Board Geometry/Soldermask Top")
		(3 "B.Mask" user "Board Geometry/Soldermask Bottom")
		(17 "Dwgs.User" user "User.Drawings")
		(19 "Cmts.User" user "User.Comments")
		(21 "Eco1.User" user "User.Eco1")
		(23 "Eco2.User" user "User.Eco2")
		(25 "Edge.Cuts" user "Board Geometry/Outline")
		(27 "Margin" user)
		(31 "F.CrtYd" user "Package Geometry/Place Bound Top")
		(29 "B.CrtYd" user "Package Geometry/Place Bound Bottom")
		(35 "F.Fab" user "Ref Des/Assembly Top")
		(33 "B.Fab" user "Ref Des/Assembly Bottom")
	)
	(footprint ""
		(layer "F.Cu")
		(at 48.387 -132.588 180)
		(property "Reference" "D13"
			(at 0 0 180)
			(layer "F.SilkS")
			(hide yes)
			(effects
				(font
					(size 1.27 1.27)
				)
			)
		)
		(property "Value" "RB551V30-GP"
			(at 0 -6.7818 180)
			(unlocked yes)
			(layer "F.Fab")
			(hide yes)
			(effects
				(font
					(size 1.016 1.016)
					(thickness 0.1524)
				)
			)
		)
		(property "Device Type" "SOD323AKH38"
			(at 0 -8.6868 180)
			(unlocked yes)
			(layer "F.Fab")
			(hide yes)
			(effects
				(font
					(size 1.016 1.016)
					(thickness 0.1524)
				)
			)
		)
		(duplicate_pad_numbers_are_jumpers no)
		(fp_line
			(start 0.889 2.159)
			(end -0.889 2.159)
			(stroke
				(width 0.1524)
				(type default)
			)
			(layer "F.SilkS")
		)
		(fp_line
			(start 0.889 -1.9304)
			(end 0.889 2.159)
			(stroke
				(width 0.1524)
				(type default)
			)
			(layer "F.SilkS")
		)
		(fp_line
			(start 0.762 2.0574)
			(end -0.762 2.0574)
			(stroke
				(width 0.508)
				(type default)
			)
			(layer "F.SilkS")
		)
		(fp_line
			(start -0.889 2.159)
			(end -0.889 -1.9304)
			(stroke
				(width 0.1524)
				(type default)
			)
			(layer "F.SilkS")
		)
		(fp_line
			(start -0.889 -1.9304)
			(end 0.889 -1.9304)
			(stroke
				(width 0.1524)
				(type default)
			)
			(layer "F.SilkS")
		)
		(fp_rect
			(start -1.016 2.3114)
			(end 1.016 -2.0066)
			(stroke
				(width 0)
				(type default)
			)
			(fill no)
			(layer "F.CrtYd")
		)
		(fp_poly
			(pts
				(xy -1.016 -2.0066) (xy 1.016 -2.0066) (xy 1.016 2.3114) (xy -1.016 2.3114)
			)
			(stroke
				(width 0)
				(type default)
			)
			(fill no)
			(layer "F.Fab")
		)
		(pad "A" smd rect
			(at 0 -1.143 180)
			(size 0.5588 1.016)
			(layers "F.Cu" "F.Mask" "F.Paste")
			(net "SW_HDD_R13")
		)
		(pad "K" smd rect
			(at 0 1.143 180)
			(size 0.5588 1.016)
			(layers "F.Cu" "F.Mask" "F.Paste")
			(net "SW_HDD_N13")
		)
	)
	(footprint ""
		(layer "F.Cu")
		(at 20.500086 -377.219972 180)
		(property "Reference" "FLED1"
			(at 0 0 180)
			(layer "F.SilkS")
			(hide yes)
			(effects
				(font
					(size 1.27 1.27)
				)
			)
		)
		(property "Value" "LED-BY-14-GP"
			(at -4.7752 -2.1844 180)
			(unlocked yes)
			(layer "F.Fab")
			(hide yes)
			(effects
				(font
					(size 1.016 1.016)
					(thickness 0.1524)
				)
			)
		)
		(property "Device Type" "LED-100-3PH206"
			(at -4.7752 -3.7084 180)
			(unlocked yes)
			(layer "F.Fab")
			(hide yes)
			(effects
				(font
					(size 1.016 1.016)
					(thickness 0.1524)
				)
			)
		)
		(duplicate_pad_numbers_are_jumpers no)
		(fp_line
			(start 3.7592 8.0264)
			(end -3.7592 8.0264)
			(stroke
				(width 0.1524)
				(type default)
			)
			(layer "F.SilkS")
		)
		(fp_line
			(start 3.7592 -1.524)
			(end 3.7592 8.0264)
			(stroke
				(width 0.1524)
				(type default)
			)
			(layer "F.SilkS")
		)
		(fp_line
			(start 1.87833 3.63474)
			(end 0.58293 2.33934)
			(stroke
				(width 0.1524)
				(type default)
			)
			(layer "F.SilkS")
		)
		(fp_line
			(start 1.87833 2.33934)
			(end 2.81813 2.33934)
			(stroke
				(width 0.1524)
				(type default)
			)
			(layer "F.SilkS")
		)
		(fp_line
			(start 1.87833 1.04394)
			(end 1.87833 3.63474)
			(stroke
				(width 0.1524)
				(type default)
			)
			(layer "F.SilkS")
		)
		(fp_line
			(start 0.58293 3.05054)
			(end 0.58293 1.42494)
			(stroke
				(width 0.1524)
				(type default)
			)
			(layer "F.SilkS")
		)
		(fp_line
			(start 0.58293 2.33934)
			(end 1.87833 1.04394)
			(stroke
				(width 0.1524)
				(type default)
			)
			(layer "F.SilkS")
		)
		(fp_line
			(start -0.45847 3.05054)
			(end -0.45847 1.42494)
			(stroke
				(width 0.1524)
				(type default)
			)
			(layer "F.SilkS")
		)
		(fp_line
			(start -0.45847 2.33934)
			(end 0.58293 2.33934)
			(stroke
				(width 0.1524)
				(type default)
			)
			(layer "F.SilkS")
		)
		(fp_line
			(start -0.45847 2.33934)
			(end -1.75387 1.04394)
			(stroke
				(width 0.1524)
				(type default)
			)
			(layer "F.SilkS")
		)
		(fp_line
			(start -1.75387 3.63474)
			(end -0.45847 2.33934)
			(stroke
				(width 0.1524)
				(type default)
			)
			(layer "F.SilkS")
		)
		(fp_line
			(start -1.75387 2.33934)
			(end -3.45567 2.33934)
			(stroke
				(width 0.1524)
				(type default)
			)
			(layer "F.SilkS")
		)
		(fp_line
			(start -1.75387 1.04394)
			(end -1.75387 3.63474)
			(stroke
				(width 0.1524)
				(type default)
			)
			(layer "F.SilkS")
		)
		(fp_line
			(start -3.7592 8.0264)
			(end -3.7592 -1.524)
			(stroke
				(width 0.1524)
				(type default)
			)
			(layer "F.SilkS")
		)
		(fp_line
			(start -3.7592 -1.524)
			(end 3.7592 -1.524)
			(stroke
				(width 0.1524)
				(type default)
			)
			(layer "F.SilkS")
		)
		(fp_circle
			(center 2.54 0)
			(end 1.5494 0)
			(stroke
				(width 0.3048)
				(type default)
			)
			(fill no)
			(layer "F.SilkS")
		)
		(fp_circle
			(center 0 0)
			(end -0.9906 0)
			(stroke
				(width 0.3048)
				(type default)
			)
			(fill no)
			(layer "F.SilkS")
		)
		(fp_circle
			(center -2.54 0)
			(end -3.5306 0)
			(stroke
				(width 0.3048)
				(type default)
			)
			(fill no)
			(layer "F.SilkS")
		)
		(fp_rect
			(start -3.5052 7.7724)
			(end 3.5052 -1.27)
			(stroke
				(width 0)
				(type default)
			)
			(fill no)
			(layer "F.CrtYd")
		)
		(fp_poly
			(pts
				(xy -4.0132 8.2804) (xy -4.0132 -1.778) (xy -3.5052 -1.778) (xy -3.5052 7.7724) (xy 3.5052 7.7724)
				(xy 3.5052 -1.27) (xy -3.50012 -1.27) (xy -3.50012 -1.778) (xy 4.0132 -1.778) (xy 4.0132 8.2804)
			)
			(stroke
				(width 0)
				(type default)
			)
			(fill no)
			(layer "F.CrtYd")
		)
		(fp_rect
			(start -4.0132 8.2804)
			(end 4.0132 -1.778)
			(stroke
				(width 0)
				(type default)
			)
			(fill no)
			(layer "F.Fab")
		)
		(pad "1" thru_hole circle
			(at -2.54 0 180)
			(size 1.27 1.27)
			(drill 0.889)
			(layers "*.Cu" "*.Mask")
			(remove_unused_layers no)
			(net "FAN_LED_BLUE0")
			(clearance 0.1651)
			(thermal_gap 0.1651)
		)
		(pad "2" thru_hole circle
			(at 0 0 180)
			(size 1.27 1.27)
			(drill 0.889)
			(layers "*.Cu" "*.Mask")
			(remove_unused_layers no)
			(net "GND")
			(clearance 0.1651)
			(thermal_gap 0.1651)
		)
		(pad "3" thru_hole circle
			(at 2.54 0 180)
			(size 1.27 1.27)
			(drill 0.889)
			(layers "*.Cu" "*.Mask")
			(remove_unused_layers no)
			(net "FAN_LED_YELLOW_0")
			(clearance 0.1651)
			(thermal_gap 0.1651)
		)
	)
	(footprint ""
		(layer "F.Cu")
		(at 117.5766 -248.412 -90)
		(property "Reference" "R212"
			(at 0 0 270)
			(layer "F.SilkS")
			(hide yes)
			(effects
				(font
					(size 1.27 1.27)
				)
			)
		)
		(property "Value" "1KR2F-3-GP"
			(at 0.064008 -3.993896 270)
			(unlocked yes)
			(layer "F.Fab")
			(hide yes)
			(effects
				(font
					(size 1.016 1.016)
					(thickness 0.1524)
				)
			)
		)
		(property "Device Type" "R402H16"
			(at 0.064008 -5.517896 270)
			(unlocked yes)
			(layer "F.Fab")
			(hide yes)
			(effects
				(font
					(size 1.016 1.016)
					(thickness 0.1524)
				)
			)
		)
		(duplicate_pad_numbers_are_jumpers no)
		(fp_line
			(start -0.508 -0.9398)
			(end -0.508 0.9398)
			(stroke
				(width 0.1524)
				(type default)
			)
			(layer "F.SilkS")
		)
		(fp_line
			(start 0.508 -0.9398)
			(end -0.508 -0.9398)
			(stroke
				(width 0.1524)
				(type default)
			)
			(layer "F.SilkS")
		)
		(fp_rect
			(start -0.508 0.9398)
			(end 0.508 -0.9398)
			(stroke
				(width 0)
				(type default)
			)
			(fill no)
			(layer "F.CrtYd")
		)
		(fp_rect
			(start -0.508 0.9398)
			(end 0.508 -0.9398)
			(stroke
				(width 0)
				(type default)
			)
			(fill no)
			(layer "F.Fab")
		)
		(pad "1" smd custom
			(at 0 -0.4445 270)
			(size 0.1397 0.1397)
			(layers "F.Cu" "F.Mask" "F.Paste")
			(net "P3V3_STBY_B")
			(options
				(clearance outline)
				(anchor circle)
			)
			(primitives
				(gr_poly
					(pts
						(arc
							(start -0.1778 -0.2794)
							(mid -0.249642 -0.249642)
							(end -0.2794 -0.1778)
						)
						(arc
							(start -0.2794 0.1778)
							(mid -0.249642 0.249642)
							(end -0.1778 0.2794)
						)
						(arc
							(start 0.1778 0.2794)
							(mid 0.249642 0.249642)
							(end 0.2794 0.1778)
						)
						(arc
							(start 0.2794 -0.1778)
							(mid 0.249642 -0.249642)
							(end 0.1778 -0.2794)
						)
					)
					(width 0)
					(fill yes)
				)
			)
		)
		(pad "2" smd custom
			(at 0 0.4445 270)
			(size 0.1397 0.1397)
			(layers "F.Cu" "F.Mask" "F.Paste")
			(net "SW_PWR_R_HDD3")
			(options
				(clearance outline)
				(anchor circle)
			)
			(primitives
				(gr_poly
					(pts
						(arc
							(start -0.1778 -0.2794)
							(mid -0.249642 -0.249642)
							(end -0.2794 -0.1778)
						)
						(arc
							(start -0.2794 0.1778)
							(mid -0.249642 0.249642)
							(end -0.1778 0.2794)
						)
						(arc
							(start 0.1778 0.2794)
							(mid 0.249642 0.249642)
							(end 0.2794 0.1778)
						)
						(arc
							(start 0.2794 -0.1778)
							(mid 0.249642 -0.249642)
							(end 0.1778 -0.2794)
						)
					)
					(width 0)
					(fill yes)
				)
			)
		)
	)
	(footprint ""
		(layer "F.Cu")
		(at 255.8796 -286.8422 90)
		(property "Reference" "R1173"
			(at 0 0 90)
			(layer "F.SilkS")
			(hide yes)
			(effects
				(font
					(size 1.27 1.27)
				)
			)
		)
		(property "Value" "2D2R3-1-U-GP"
			(at -0.0254 -2.5146 90)
			(unlocked yes)
			(layer "F.Fab")
			(hide yes)
			(effects
				(font
					(size 1.016 1.016)
					(thickness 0.1524)
				)
			)
		)
		(property "Device Type" "R603H22"
			(at -0.0254 -4.0386 90)
			(unlocked yes)
			(layer "F.Fab")
			(hide yes)
			(effects
				(font
					(size 1.016 1.016)
					(thickness 0.1524)
				)
			)
		)
		(duplicate_pad_numbers_are_jumpers no)
		(fp_line
			(start 0.2032 0)
			(end 0.4826 0)
			(stroke
				(width 0.2032)
				(type default)
			)
			(layer "F.SilkS")
		)
		(fp_line
			(start -0.4826 0)
			(end -0.2032 0)
			(stroke
				(width 0.2032)
				(type default)
			)
			(layer "F.SilkS")
		)
		(fp_rect
			(start -0.5842 1.3335)
			(end 0.5842 -1.3335)
			(stroke
				(width 0)
				(type default)
			)
			(fill no)
			(layer "F.CrtYd")
		)
		(fp_rect
			(start -0.5842 1.3335)
			(end 0.5842 -1.3335)
			(stroke
				(width 0)
				(type default)
			)
			(fill no)
			(layer "F.Fab")
		)
		(pad "1" smd custom
			(at 0 -0.762 90)
			(size 0.2159 0.2159)
			(layers "F.Cu" "F.Mask" "F.Paste")
			(net "P3V3_STBY_VCC")
			(options
				(clearance outline)
				(anchor circle)
			)
			(primitives
				(gr_poly
					(pts
						(arc
							(start -0.3302 -0.4318)
							(mid -0.402042 -0.402042)
							(end -0.4318 -0.3302)
						)
						(arc
							(start -0.4318 0.3302)
							(mid -0.402042 0.402042)
							(end -0.3302 0.4318)
						)
						(arc
							(start 0.3302 0.4318)
							(mid 0.402042 0.402042)
							(end 0.4318 0.3302)
						)
						(arc
							(start 0.4318 -0.3302)
							(mid 0.402042 -0.402042)
							(end 0.3302 -0.4318)
						)
					)
					(width 0)
					(fill yes)
				)
			)
		)
		(pad "2" smd custom
			(at 0 0.762 90)
			(size 0.2159 0.2159)
			(layers "F.Cu" "F.Mask" "F.Paste")
			(net "P12V_B")
			(options
				(clearance outline)
				(anchor circle)
			)
			(primitives
				(gr_poly
					(pts
						(arc
							(start -0.3302 -0.4318)
							(mid -0.402042 -0.402042)
							(end -0.4318 -0.3302)
						)
						(arc
							(start -0.4318 0.3302)
							(mid -0.402042 0.402042)
							(end -0.3302 0.4318)
						)
						(arc
							(start 0.3302 0.4318)
							(mid 0.402042 0.402042)
							(end 0.4318 0.3302)
						)
						(arc
							(start 0.4318 -0.3302)
							(mid 0.402042 -0.402042)
							(end 0.3302 -0.4318)
						)
					)
					(width 0)
					(fill yes)
				)
			)
		)
	)
	(footprint ""
		(layer "F.Cu")
		(at 473.583 -19.812 -90)
		(property "Reference" "R882"
			(at 0 0 270)
			(layer "F.SilkS")
			(hide yes)
			(effects
				(font
					(size 1.27 1.27)
				)
			)
		)
		(property "Value" "4K7R2J-2-GP"
			(at 0.064008 -3.993896 270)
			(unlocked yes)
			(layer "F.Fab")
			(hide yes)
			(effects
				(font
					(size 1.016 1.016)
					(thickness 0.1524)
				)
			)
		)
		(property "Device Type" "R402H16"
			(at 0.064008 -5.517896 270)
			(unlocked yes)
			(layer "F.Fab")
			(hide yes)
			(effects
				(font
					(size 1.016 1.016)
					(thickness 0.1524)
				)
			)
		)
		(duplicate_pad_numbers_are_jumpers no)
		(fp_line
			(start -0.508 -0.9398)
			(end -0.508 0.9398)
			(stroke
				(width 0.1524)
				(type default)
			)
			(layer "F.SilkS")
		)
		(fp_line
			(start 0.508 -0.9398)
			(end -0.508 -0.9398)
			(stroke
				(width 0.1524)
				(type default)
			)
			(layer "F.SilkS")
		)
		(fp_rect
			(start -0.508 0.9398)
			(end 0.508 -0.9398)
			(stroke
				(width 0)
				(type default)
			)
			(fill no)
			(layer "F.CrtYd")
		)
		(fp_rect
			(start -0.508 0.9398)
			(end 0.508 -0.9398)
			(stroke
				(width 0)
				(type default)
			)
			(fill no)
			(layer "F.Fab")
		)
		(pad "1" smd custom
			(at 0 -0.4445 270)
			(size 0.1397 0.1397)
			(layers "F.Cu" "F.Mask" "F.Paste")
			(net "P12V_B")
			(options
				(clearance outline)
				(anchor circle)
			)
			(primitives
				(gr_poly
					(pts
						(arc
							(start -0.1778 -0.2794)
							(mid -0.249642 -0.249642)
							(end -0.2794 -0.1778)
						)
						(arc
							(start -0.2794 0.1778)
							(mid -0.249642 0.249642)
							(end -0.1778 0.2794)
						)
						(arc
							(start 0.1778 0.2794)
							(mid 0.249642 0.249642)
							(end 0.2794 0.1778)
						)
						(arc
							(start 0.2794 -0.1778)
							(mid 0.249642 -0.249642)
							(end 0.1778 -0.2794)
						)
					)
					(width 0)
					(fill yes)
				)
			)
		)
		(pad "2" smd custom
			(at 0 0.4445 270)
			(size 0.1397 0.1397)
			(layers "F.Cu" "F.Mask" "F.Paste")
			(net "SW_HDD_P35")
			(options
				(clearance outline)
				(anchor circle)
			)
			(primitives
				(gr_poly
					(pts
						(arc
							(start -0.1778 -0.2794)
							(mid -0.249642 -0.249642)
							(end -0.2794 -0.1778)
						)
						(arc
							(start -0.2794 0.1778)
							(mid -0.249642 0.249642)
							(end -0.1778 0.2794)
						)
						(arc
							(start 0.1778 0.2794)
							(mid 0.249642 0.249642)
							(end 0.2794 0.1778)
						)
						(arc
							(start 0.2794 -0.1778)
							(mid 0.249642 -0.249642)
							(end 0.1778 -0.2794)
						)
					)
					(width 0)
					(fill yes)
				)
			)
		)
	)
	(footprint ""
		(layer "F.Cu")
		(at 384.734562 -245.219474 -90)
		(property "Reference" "C132"
			(at 0 0 270)
			(layer "F.SilkS")
			(hide yes)
			(effects
				(font
					(size 1.27 1.27)
				)
			)
		)
		(property "Value" "SCD01U16V1KX-GP"
			(at -2.8321 -1.7399 270)
			(unlocked yes)
			(layer "F.Fab")
			(hide yes)
			(effects
				(font
					(size 1.016 1.016)
					(thickness 0.1524)
				)
			)
		)
		(property "Device Type" "C0201H13"
			(at -2.8321 -3.2639 270)
			(unlocked yes)
			(layer "F.Fab")
			(hide yes)
			(effects
				(font
					(size 1.016 1.016)
					(thickness 0.1524)
				)
			)
		)
		(duplicate_pad_numbers_are_jumpers no)
		(fp_rect
			(start -0.2794 0.6477)
			(end 0.2794 -0.6477)
			(stroke
				(width 0)
				(type default)
			)
			(fill no)
			(layer "F.CrtYd")
		)
		(fp_rect
			(start -0.2794 0.6477)
			(end 0.2794 -0.6477)
			(stroke
				(width 0)
				(type default)
			)
			(fill no)
			(layer "F.Fab")
		)
		(pad "1" smd custom
			(at 0 -0.2794 270)
			(size 0.0762 0.0762)
			(layers "F.Cu" "F.Mask" "F.Paste")
			(net "SAS_HDD_RX_N8")
			(options
				(clearance outline)
				(anchor circle)
			)
			(primitives
				(gr_poly
					(pts
						(arc
							(start 0.1524 -0.127)
							(mid 0.137521 -0.162921)
							(end 0.1016 -0.1778)
						)
						(arc
							(start -0.1016 -0.1778)
							(mid -0.137521 -0.162921)
							(end -0.1524 -0.127)
						)
						(arc
							(start -0.1524 0.127)
							(mid -0.137521 0.162921)
							(end -0.1016 0.1778)
						)
						(arc
							(start 0.1016 0.1778)
							(mid 0.137521 0.162921)
							(end 0.1524 0.127)
						)
					)
					(width 0)
					(fill yes)
				)
			)
		)
		(pad "2" smd custom
			(at 0 0.2794 270)
			(size 0.0762 0.0762)
			(layers "F.Cu" "F.Mask" "F.Paste")
			(net "PHY_SCC_B_TO_DRV_B_8_DN")
			(options
				(clearance outline)
				(anchor circle)
			)
			(primitives
				(gr_poly
					(pts
						(arc
							(start 0.1524 -0.127)
							(mid 0.137521 -0.162921)
							(end 0.1016 -0.1778)
						)
						(arc
							(start -0.1016 -0.1778)
							(mid -0.137521 -0.162921)
							(end -0.1524 -0.127)
						)
						(arc
							(start -0.1524 0.127)
							(mid -0.137521 0.162921)
							(end -0.1016 0.1778)
						)
						(arc
							(start 0.1016 0.1778)
							(mid 0.137521 0.162921)
							(end 0.1524 0.127)
						)
					)
					(width 0)
					(fill yes)
				)
			)
		)
	)
	(footprint ""
		(layer "F.Cu")
		(at 22.987 -134.493 90)
		(property "Reference" "R359"
			(at 0 0 90)
			(layer "F.SilkS")
			(hide yes)
			(effects
				(font
					(size 1.27 1.27)
				)
			)
		)
		(property "Value" "4K7R2F-GP"
			(at 0.064008 -3.993896 90)
			(unlocked yes)
			(layer "F.Fab")
			(hide yes)
			(effects
				(font
					(size 1.016 1.016)
					(thickness 0.1524)
				)
			)
		)
		(property "Device Type" "R402H16"
			(at 0.064008 -5.517896 90)
			(unlocked yes)
			(layer "F.Fab")
			(hide yes)
			(effects
				(font
					(size 1.016 1.016)
					(thickness 0.1524)
				)
			)
		)
		(duplicate_pad_numbers_are_jumpers no)
		(fp_line
			(start 0.508 -0.9398)
			(end -0.508 -0.9398)
			(stroke
				(width 0.1524)
				(type default)
			)
			(layer "F.SilkS")
		)
		(fp_line
			(start -0.508 -0.9398)
			(end -0.508 0.9398)
			(stroke
				(width 0.1524)
				(type default)
			)
			(layer "F.SilkS")
		)
		(fp_rect
			(start -0.508 0.9398)
			(end 0.508 -0.9398)
			(stroke
				(width 0)
				(type default)
			)
			(fill no)
			(layer "F.CrtYd")
		)
		(fp_rect
			(start -0.508 0.9398)
			(end 0.508 -0.9398)
			(stroke
				(width 0)
				(type default)
			)
			(fill no)
			(layer "F.Fab")
		)
		(pad "1" smd custom
			(at 0 -0.4445 90)
			(size 0.1397 0.1397)
			(layers "F.Cu" "F.Mask" "F.Paste")
			(net "SW_PWR_R_HDD12")
			(options
				(clearance outline)
				(anchor circle)
			)
			(primitives
				(gr_poly
					(pts
						(arc
							(start -0.1778 -0.2794)
							(mid -0.249642 -0.249642)
							(end -0.2794 -0.1778)
						)
						(arc
							(start -0.2794 0.1778)
							(mid -0.249642 0.249642)
							(end -0.1778 0.2794)
						)
						(arc
							(start 0.1778 0.2794)
							(mid 0.249642 0.249642)
							(end 0.2794 0.1778)
						)
						(arc
							(start 0.2794 -0.1778)
							(mid 0.249642 -0.249642)
							(end 0.1778 -0.2794)
						)
					)
					(width 0)
					(fill yes)
				)
			)
		)
		(pad "2" smd custom
			(at 0 0.4445 90)
			(size 0.1397 0.1397)
			(layers "F.Cu" "F.Mask" "F.Paste")
			(net "GND")
			(options
				(clearance outline)
				(anchor circle)
			)
			(primitives
				(gr_poly
					(pts
						(arc
							(start -0.1778 -0.2794)
							(mid -0.249642 -0.249642)
							(end -0.2794 -0.1778)
						)
						(arc
							(start -0.2794 0.1778)
							(mid -0.249642 0.249642)
							(end -0.1778 0.2794)
						)
						(arc
							(start 0.1778 0.2794)
							(mid 0.249642 0.249642)
							(end 0.2794 0.1778)
						)
						(arc
							(start 0.2794 -0.1778)
							(mid 0.249642 -0.249642)
							(end 0.1778 -0.2794)
						)
					)
					(width 0)
					(fill yes)
				)
			)
		)
	)
)
